(kicad_pcb
	(version 20260206)
	(generator "pcbnew")
	(generator_version "10.0")
	(general
		(thickness 1.6)
		(legacy_teardrops no)
	)
	(paper "A4")
	(title_block
		(title "03242023_DA0F0TMBIJ0_F0T_Motherboard_J_brd_V01_OCP.brd")
		(comment 1 "Grand Teton / footprints 2811-2815 of 6105")
	)
	(layers
		(0 "F.Cu" signal "TOP")
		(4 "In1.Cu" signal "GND")
		(6 "In2.Cu" signal "IN1")
		(8 "In3.Cu" signal "GND1")
		(10 "In4.Cu" signal "IN2")
		(12 "In5.Cu" signal "GND2")
		(14 "In6.Cu" signal "IN3")
		(16 "In7.Cu" signal "GND3")
		(18 "In8.Cu" signal "VCC")
		(20 "In9.Cu" signal "VCC1")
		(22 "In10.Cu" signal "GND4")
		(24 "In11.Cu" signal "IN4")
		(26 "In12.Cu" signal "GND5")
		(28 "In13.Cu" signal "IN5")
		(30 "In14.Cu" signal "GND6")
		(32 "In15.Cu" signal "IN6")
		(34 "In16.Cu" signal "GND7")
		(2 "B.Cu" signal "BOTTOM")
		(9 "F.Adhes" user "F.Adhesive")
		(11 "B.Adhes" user "B.Adhesive")
		(13 "F.Paste" user "Package Geometry/Pastemask Top")
		(15 "B.Paste" user "Package Geometry/Pastemask Bottom")
		(5 "F.SilkS" user "Ref Des/Silkscreen Top")
		(7 "B.SilkS" user "Ref Des/Silkscreen Bottom")
		(1 "F.Mask" user "Board Geometry/Soldermask Top")
		(3 "B.Mask" user "Board Geometry/Soldermask Bottom")
		(17 "Dwgs.User" user "User.Drawings")
		(19 "Cmts.User" user "User.Comments")
		(21 "Eco1.User" user "User.Eco1")
		(23 "Eco2.User" user "User.Eco2")
		(25 "Edge.Cuts" user "Board Geometry/Outline")
		(27 "Margin" user)
		(31 "F.CrtYd" user "Package Geometry/Place Bound Top")
		(29 "B.CrtYd" user "Package Geometry/Place Bound Bottom")
		(35 "F.Fab" user "Ref Des/Assembly Top")
		(33 "B.Fab" user "Ref Des/Assembly Bottom")
	)
	(footprint ""
		(layer "F.Cu")
		(at 76.869798 -408.517344 -90)
		(property "Reference" "C690"
			(at 0 0 270)
			(layer "F.SilkS")
			(hide yes)
			(effects
				(font
					(size 1.27 1.27)
				)
			)
		)
		(property "Value" ""
			(at 0 0 270)
			(layer "F.Fab")
			(effects
				(font
					(size 1.27 1.27)
				)
			)
		)
		(duplicate_pad_numbers_are_jumpers no)
		(fp_line
			(start -0.299974 0.150114)
			(end -0.299974 -0.150114)
			(stroke
				(width 0.1)
				(type default)
			)
			(layer "F.Fab")
		)
		(fp_line
			(start 0.299974 0.150114)
			(end -0.299974 0.150114)
			(stroke
				(width 0.1)
				(type default)
			)
			(layer "F.Fab")
		)
		(fp_line
			(start -0.299974 -0.150114)
			(end 0.299974 -0.150114)
			(stroke
				(width 0.1)
				(type default)
			)
			(layer "F.Fab")
		)
		(fp_line
			(start 0.299974 -0.150114)
			(end 0.299974 0.150114)
			(stroke
				(width 0.1)
				(type default)
			)
			(layer "F.Fab")
		)
		(pad "1" smd rect
			(at -0.2667 0 270)
			(size 0.3048 0.381)
			(layers "F.Cu" "F.Mask" "F.Paste")
			(net "P5E_CPU1_PE4_TX_C_DN<9>")
		)
		(pad "2" smd rect
			(at 0.2667 0 270)
			(size 0.3048 0.381)
			(layers "F.Cu" "F.Mask" "F.Paste")
			(net "P5E_CPU1_PE4_TX_DN<9>")
		)
	)
	(footprint ""
		(layer "F.Cu")
		(at 426.630084 -44.619926)
		(property "Reference" "J104"
			(at 1.19126 -2.926588 0)
			(unlocked yes)
			(layer "F.SilkS")
			(effects
				(font
					(size 0.7874 0.5842)
					(thickness 0.1524)
				)
				(justify left)
			)
		)
		(property "Value" ""
			(at 0 0 0)
			(layer "F.Fab")
			(effects
				(font
					(size 1.27 1.27)
				)
			)
		)
		(duplicate_pad_numbers_are_jumpers no)
		(fp_line
			(start -1.230122 -1.27)
			(end -1.230122 16.51)
			(stroke
				(width 0.1524)
				(type default)
			)
			(layer "F.SilkS")
		)
		(fp_line
			(start -1.230122 16.51)
			(end 3.770122 16.51)
			(stroke
				(width 0.1524)
				(type default)
			)
			(layer "F.SilkS")
		)
		(fp_line
			(start 3.770122 -1.27)
			(end -1.230122 -1.27)
			(stroke
				(width 0.1524)
				(type default)
			)
			(layer "F.SilkS")
		)
		(fp_line
			(start 3.770122 16.51)
			(end 3.770122 -1.27)
			(stroke
				(width 0.1524)
				(type default)
			)
			(layer "F.SilkS")
		)
		(fp_poly
			(pts
				(xy 0.45974 -2.63144) (xy -0.04826 -1.61544) (xy -0.55626 -2.63144)
			)
			(stroke
				(width 0)
				(type default)
			)
			(fill yes)
			(layer "F.SilkS")
		)
		(fp_line
			(start -1.230122 -1.27)
			(end -1.230122 16.51)
			(stroke
				(width 0.1)
				(type default)
			)
			(layer "F.Fab")
		)
		(fp_line
			(start -1.230122 16.51)
			(end 3.770122 16.51)
			(stroke
				(width 0.1)
				(type default)
			)
			(layer "F.Fab")
		)
		(fp_line
			(start 3.770122 -1.27)
			(end -1.230122 -1.27)
			(stroke
				(width 0.1)
				(type default)
			)
			(layer "F.Fab")
		)
		(fp_line
			(start 3.770122 16.51)
			(end 3.770122 -1.27)
			(stroke
				(width 0.1)
				(type default)
			)
			(layer "F.Fab")
		)
		(fp_poly
			(pts
				(xy 0.508 -2.5146) (xy -0.508 -2.5146) (xy 0 -1.4986)
			)
			(stroke
				(width 0)
				(type default)
			)
			(fill yes)
			(layer "F.Fab")
		)
		(fp_text user "13"
			(at -0.684022 17.95145 0)
			(unlocked yes)
			(layer "F.SilkS")
			(effects
				(font
					(size 0.7874 0.5842)
					(thickness 0.1524)
				)
				(justify left)
			)
		)
		(fp_text user "14"
			(at 1.855978 17.95145 0)
			(unlocked yes)
			(layer "F.SilkS")
			(effects
				(font
					(size 0.7874 0.5842)
					(thickness 0.1524)
				)
				(justify left)
			)
		)
		(fp_text user "2"
			(at 4.372356 -1.470152 0)
			(unlocked yes)
			(layer "F.SilkS")
			(effects
				(font
					(size 0.7874 0.5842)
					(thickness 0.1524)
				)
				(justify left)
			)
		)
		(fp_text user "1"
			(at 0.026416 -2.300732 0)
			(unlocked yes)
			(layer "B.SilkS")
			(effects
				(font
					(size 0.7874 0.5842)
					(thickness 0.1524)
				)
				(justify left mirror)
			)
		)
		(fp_text user "13"
			(at 0.524256 17.173448 0)
			(unlocked yes)
			(layer "B.SilkS")
			(effects
				(font
					(size 0.7874 0.5842)
					(thickness 0.1524)
				)
				(justify left mirror)
			)
		)
		(fp_text user "2"
			(at 3.356356 -1.955292 0)
			(unlocked yes)
			(layer "B.SilkS")
			(effects
				(font
					(size 0.7874 0.5842)
					(thickness 0.1524)
				)
				(justify left mirror)
			)
		)
		(fp_text user "14"
			(at 4.273296 17.249648 0)
			(unlocked yes)
			(layer "B.SilkS")
			(effects
				(font
					(size 0.7874 0.5842)
					(thickness 0.1524)
				)
				(justify left mirror)
			)
		)
		(fp_text user "1"
			(at 0.091948 -0.9779 270)
			(unlocked yes)
			(layer "B.Fab")
			(effects
				(font
					(size 0.7874 0.5842)
					(thickness 0.1524)
				)
				(justify left mirror)
			)
		)
		(fp_text user "13"
			(at 0.091948 17.7038 270)
			(unlocked yes)
			(layer "B.Fab")
			(effects
				(font
					(size 0.7874 0.5842)
					(thickness 0.1524)
				)
				(justify left mirror)
			)
		)
		(fp_text user "2"
			(at 2.631948 -0.9779 270)
			(unlocked yes)
			(layer "B.Fab")
			(effects
				(font
					(size 0.7874 0.5842)
					(thickness 0.1524)
				)
				(justify left mirror)
			)
		)
		(fp_text user "14"
			(at 2.631948 17.7038 270)
			(unlocked yes)
			(layer "B.Fab")
			(effects
				(font
					(size 0.7874 0.5842)
					(thickness 0.1524)
				)
				(justify left mirror)
			)
		)
		(fp_text user "13"
			(at 0.091948 16.5862 270)
			(unlocked yes)
			(layer "F.Fab")
			(effects
				(font
					(size 0.7874 0.5842)
					(thickness 0.1524)
				)
				(justify left)
			)
		)
		(fp_text user "2"
			(at 2.631948 -2.0701 270)
			(unlocked yes)
			(layer "F.Fab")
			(effects
				(font
					(size 0.7874 0.5842)
					(thickness 0.1524)
				)
				(justify left)
			)
		)
		(fp_text user "14"
			(at 2.631948 16.5862 270)
			(unlocked yes)
			(layer "F.Fab")
			(effects
				(font
					(size 0.7874 0.5842)
					(thickness 0.1524)
				)
				(justify left)
			)
		)
		(pad "1" thru_hole rect
			(at 0 0 270)
			(size 1.5494 1.5494)
			(drill 1.0414)
			(layers "*.Cu" "*.Mask")
			(remove_unused_layers no)
			(net "PU_ESPI_ENABLE_STRAP")
			(clearance 0)
			(padstack
				(mode front_inner_back)
				(layer "Inner"
					(shape circle)
					(size 1.5494 1.5494)
					(clearance 0)
				)
				(layer "B.Cu"
					(shape rect)
					(size 1.5494 1.5494)
					(clearance 0)
				)
			)
		)
		(pad "2" thru_hole circle
			(at 2.54 0 270)
			(size 1.5494 1.5494)
			(drill 1.0414)
			(layers "*.Cu" "*.Mask")
			(remove_unused_layers no)
			(net "JTAG_TRC_PCH_PTI<6>")
			(clearance 0)
		)
		(pad "3" thru_hole circle
			(at 0 2.54 270)
			(size 1.5494 1.5494)
			(drill 1.0414)
			(layers "*.Cu" "*.Mask")
			(remove_unused_layers no)
			(net "PU_BIOS_RCVR_BOOT")
			(clearance 0)
		)
		(pad "4" thru_hole circle
			(at 2.54 2.54 270)
			(size 1.5494 1.5494)
			(drill 1.0414)
			(layers "*.Cu" "*.Mask")
			(remove_unused_layers no)
			(net "FM_PCH_BIOS_RCVR_MODE")
			(clearance 0)
		)
		(pad "5" thru_hole circle
			(at 0 5.08 270)
			(size 1.5494 1.5494)
			(drill 1.0414)
			(layers "*.Cu" "*.Mask")
			(remove_unused_layers no)
			(net "PU_SWAP_OVERRIDE_N")
			(clearance 0)
		)
		(pad "6" thru_hole circle
			(at 2.54 5.08 270)
			(size 1.5494 1.5494)
			(drill 1.0414)
			(layers "*.Cu" "*.Mask")
			(remove_unused_layers no)
			(net "FM_ADR_COMPLETE")
			(clearance 0)
		)
		(pad "7" thru_hole circle
			(at 0 7.62 270)
			(size 1.5494 1.5494)
			(drill 1.0414)
			(layers "*.Cu" "*.Mask")
			(remove_unused_layers no)
			(net "PD_BIOS_IMAGE_SWAP_N")
			(clearance 0)
		)
		(pad "8" thru_hole circle
			(at 2.54 7.62 270)
			(size 1.5494 1.5494)
			(drill 1.0414)
			(layers "*.Cu" "*.Mask")
			(remove_unused_layers no)
			(net "FM_BIOS_IMAGE_SWAP_N")
			(clearance 0)
		)
		(pad "9" thru_hole circle
			(at 0 10.16 270)
			(size 1.5494 1.5494)
			(drill 1.0414)
			(layers "*.Cu" "*.Mask")
			(remove_unused_layers no)
			(net "PU_FLASH_SECURITY_STRAP")
			(clearance 0)
		)
		(pad "10" thru_hole circle
			(at 2.54 10.16 270)
			(size 1.5494 1.5494)
			(drill 1.0414)
			(layers "*.Cu" "*.Mask")
			(remove_unused_layers no)
			(net "FM_FLASH_SECURITY_STRAP")
			(clearance 0)
		)
		(pad "11" thru_hole circle
			(at 0 12.7 270)
			(size 1.5494 1.5494)
			(drill 1.0414)
			(layers "*.Cu" "*.Mask")
			(remove_unused_layers no)
			(net "PD_ME_RCVR_N")
			(clearance 0)
		)
		(pad "12" thru_hole circle
			(at 2.54 12.7 270)
			(size 1.5494 1.5494)
			(drill 1.0414)
			(layers "*.Cu" "*.Mask")
			(remove_unused_layers no)
			(net "FM_ME_RCVR_N")
			(clearance 0)
		)
		(pad "13" thru_hole circle
			(at 0 15.24 270)
			(size 1.5494 1.5494)
			(drill 1.0414)
			(layers "*.Cu" "*.Mask")
			(remove_unused_layers no)
			(net "PD_PASSWORD_CLEAR")
			(clearance 0)
		)
		(pad "14" thru_hole circle
			(at 2.54 15.24 270)
			(size 1.5494 1.5494)
			(drill 1.0414)
			(layers "*.Cu" "*.Mask")
			(remove_unused_layers no)
			(net "FM_PASSWORD_CLEAR_N")
			(clearance 0)
		)
	)
	(footprint ""
		(layer "F.Cu")
		(at 355.219 -390.439148 180)
		(property "Reference" "R4570"
			(at 0 0 180)
			(layer "F.SilkS")
			(hide yes)
			(effects
				(font
					(size 1.27 1.27)
				)
			)
		)
		(property "Value" ""
			(at 0 0 180)
			(layer "F.Fab")
			(effects
				(font
					(size 1.27 1.27)
				)
			)
		)
		(duplicate_pad_numbers_are_jumpers no)
		(fp_line
			(start 0.7874 0.4064)
			(end -0.7874 0.4064)
			(stroke
				(width 0.1524)
				(type default)
			)
			(layer "F.SilkS")
		)
		(fp_line
			(start 0.7874 -0.4064)
			(end 0.7874 0.4064)
			(stroke
				(width 0.1524)
				(type default)
			)
			(layer "F.SilkS")
		)
		(fp_line
			(start -0.7874 0.4064)
			(end -0.7874 -0.4064)
			(stroke
				(width 0.1524)
				(type default)
			)
			(layer "F.SilkS")
		)
		(fp_line
			(start -0.7874 -0.4064)
			(end 0.7874 -0.4064)
			(stroke
				(width 0.1524)
				(type default)
			)
			(layer "F.SilkS")
		)
		(fp_line
			(start 0.67945 0.3048)
			(end 0.120396 0.3048)
			(stroke
				(width 0.1)
				(type default)
			)
			(layer "F.Fab")
		)
		(fp_line
			(start 0.67945 -0.3048)
			(end 0.67945 0.3048)
			(stroke
				(width 0.1)
				(type default)
			)
			(layer "F.Fab")
		)
		(fp_line
			(start 0.12065 -0.2794)
			(end 0.12065 -0.3048)
			(stroke
				(width 0.1)
				(type default)
			)
			(layer "F.Fab")
		)
		(fp_line
			(start 0.12065 -0.3048)
			(end 0.67945 -0.3048)
			(stroke
				(width 0.1)
				(type default)
			)
			(layer "F.Fab")
		)
		(fp_line
			(start 0.120396 0.3048)
			(end 0.120396 0.2794)
			(stroke
				(width 0.1)
				(type default)
			)
			(layer "F.Fab")
		)
		(fp_line
			(start 0.120396 0.2794)
			(end -0.12065 0.2794)
			(stroke
				(width 0.1)
				(type default)
			)
			(layer "F.Fab")
		)
		(fp_line
			(start -0.12065 0.3048)
			(end -0.67945 0.3048)
			(stroke
				(width 0.1)
				(type default)
			)
			(layer "F.Fab")
		)
		(fp_line
			(start -0.12065 0.2794)
			(end -0.12065 0.3048)
			(stroke
				(width 0.1)
				(type default)
			)
			(layer "F.Fab")
		)
		(fp_line
			(start -0.12065 -0.2794)
			(end 0.12065 -0.2794)
			(stroke
				(width 0.1)
				(type default)
			)
			(layer "F.Fab")
		)
		(fp_line
			(start -0.12065 -0.305054)
			(end -0.12065 -0.2794)
			(stroke
				(width 0.1)
				(type default)
			)
			(layer "F.Fab")
		)
		(fp_line
			(start -0.67945 0.3048)
			(end -0.67945 -0.305054)
			(stroke
				(width 0.1)
				(type default)
			)
			(layer "F.Fab")
		)
		(fp_line
			(start -0.67945 -0.305054)
			(end -0.12065 -0.305054)
			(stroke
				(width 0.1)
				(type default)
			)
			(layer "F.Fab")
		)
		(pad "1" smd circle
			(at -0.40005 0 180)
			(size 0 0)
			(layers "F.Cu" "F.Mask" "F.Paste")
			(net "GPU_3V3IO_RSVD3")
		)
		(pad "2" smd circle
			(at 0.40005 0 180)
			(size 0 0)
			(layers "F.Cu" "F.Mask" "F.Paste")
			(net "GPU_3V3IO_RSVD3_ISO")
		)
	)
	(footprint ""
		(layer "F.Cu")
		(at 300.21022 -419.02761 -90)
		(property "Reference" "R4122"
			(at 0 0 270)
			(layer "F.SilkS")
			(hide yes)
			(effects
				(font
					(size 1.27 1.27)
				)
			)
		)
		(property "Value" ""
			(at 0 0 270)
			(layer "F.Fab")
			(effects
				(font
					(size 1.27 1.27)
				)
			)
		)
		(duplicate_pad_numbers_are_jumpers no)
		(fp_line
			(start -0.7874 0.4064)
			(end -0.7874 -0.4064)
			(stroke
				(width 0.1524)
				(type default)
			)
			(layer "F.SilkS")
		)
		(fp_line
			(start 0.7874 0.4064)
			(end -0.7874 0.4064)
			(stroke
				(width 0.1524)
				(type default)
			)
			(layer "F.SilkS")
		)
		(fp_line
			(start -0.7874 -0.4064)
			(end 0.7874 -0.4064)
			(stroke
				(width 0.1524)
				(type default)
			)
			(layer "F.SilkS")
		)
		(fp_line
			(start 0.7874 -0.4064)
			(end 0.7874 0.4064)
			(stroke
				(width 0.1524)
				(type default)
			)
			(layer "F.SilkS")
		)
		(fp_line
			(start -0.67945 0.3048)
			(end -0.67945 -0.305054)
			(stroke
				(width 0.1)
				(type default)
			)
			(layer "F.Fab")
		)
		(fp_line
			(start -0.12065 0.3048)
			(end -0.67945 0.3048)
			(stroke
				(width 0.1)
				(type default)
			)
			(layer "F.Fab")
		)
		(fp_line
			(start 0.120396 0.3048)
			(end 0.120396 0.2794)
			(stroke
				(width 0.1)
				(type default)
			)
			(layer "F.Fab")
		)
		(fp_line
			(start 0.67945 0.3048)
			(end 0.120396 0.3048)
			(stroke
				(width 0.1)
				(type default)
			)
			(layer "F.Fab")
		)
		(fp_line
			(start -0.12065 0.2794)
			(end -0.12065 0.3048)
			(stroke
				(width 0.1)
				(type default)
			)
			(layer "F.Fab")
		)
		(fp_line
			(start 0.120396 0.2794)
			(end -0.12065 0.2794)
			(stroke
				(width 0.1)
				(type default)
			)
			(layer "F.Fab")
		)
		(fp_line
			(start -0.12065 -0.2794)
			(end 0.12065 -0.2794)
			(stroke
				(width 0.1)
				(type default)
			)
			(layer "F.Fab")
		)
		(fp_line
			(start 0.12065 -0.2794)
			(end 0.12065 -0.3048)
			(stroke
				(width 0.1)
				(type default)
			)
			(layer "F.Fab")
		)
		(fp_line
			(start 0.12065 -0.3048)
			(end 0.67945 -0.3048)
			(stroke
				(width 0.1)
				(type default)
			)
			(layer "F.Fab")
		)
		(fp_line
			(start 0.67945 -0.3048)
			(end 0.67945 0.3048)
			(stroke
				(width 0.1)
				(type default)
			)
			(layer "F.Fab")
		)
		(fp_line
			(start -0.67945 -0.305054)
			(end -0.12065 -0.305054)
			(stroke
				(width 0.1)
				(type default)
			)
			(layer "F.Fab")
		)
		(fp_line
			(start -0.12065 -0.305054)
			(end -0.12065 -0.2794)
			(stroke
				(width 0.1)
				(type default)
			)
			(layer "F.Fab")
		)
		(pad "1" smd circle
			(at -0.40005 0 270)
			(size 0 0)
			(layers "F.Cu" "F.Mask" "F.Paste")
			(net "PRSNT_CABLE_GPU_B3_N")
		)
		(pad "2" smd circle
			(at 0.40005 0 270)
			(size 0 0)
			(layers "F.Cu" "F.Mask" "F.Paste")
			(net "GND")
		)
	)
	(footprint ""
		(layer "F.Cu")
		(at 407.91257 -157.691328)
		(property "Reference" "PC641"
			(at 0 0 0)
			(layer "F.SilkS")
			(hide yes)
			(effects
				(font
					(size 1.27 1.27)
				)
			)
		)
		(property "Value" ""
			(at 0 0 0)
			(layer "F.Fab")
			(effects
				(font
					(size 1.27 1.27)
				)
			)
		)
		(duplicate_pad_numbers_are_jumpers no)
		(fp_line
			(start -1.524 -0.762)
			(end 1.524 -0.762)
			(stroke
				(width 0.1524)
				(type default)
			)
			(layer "F.SilkS")
		)
		(fp_line
			(start -1.524 0.762)
			(end -1.524 -0.762)
			(stroke
				(width 0.1524)
				(type default)
			)
			(layer "F.SilkS")
		)
		(fp_line
			(start 1.524 -0.762)
			(end 1.524 0.762)
			(stroke
				(width 0.1524)
				(type default)
			)
			(layer "F.SilkS")
		)
		(fp_line
			(start 1.524 0.762)
			(end -1.524 0.762)
			(stroke
				(width 0.1524)
				(type default)
			)
			(layer "F.SilkS")
		)
		(fp_line
			(start -1.1049 -0.724916)
			(end -1.1049 0.724916)
			(stroke
				(width 0.1)
				(type default)
			)
			(layer "F.Fab")
		)
		(fp_line
			(start -1.1049 0.724916)
			(end 1.1049 0.724916)
			(stroke
				(width 0.1)
				(type default)
			)
			(layer "F.Fab")
		)
		(fp_line
			(start 1.1049 -0.724916)
			(end -1.1049 -0.724916)
			(stroke
				(width 0.1)
				(type default)
			)
			(layer "F.Fab")
		)
		(fp_line
			(start 1.1049 0.724916)
			(end 1.1049 -0.724916)
			(stroke
				(width 0.1)
				(type default)
			)
			(layer "F.Fab")
		)
		(pad "1" smd rect
			(at -0.889 0 180)
			(size 1.016 1.27)
			(layers "F.Cu" "F.Mask" "F.Paste")
			(net "PVCCD_HV_CPU0")
		)
		(pad "2" smd rect
			(at 0.889 0 180)
			(size 1.016 1.27)
			(layers "F.Cu" "F.Mask" "F.Paste")
			(net "GND")
		)
	)
)
